(kicad_pcb
	(version 20260206)
	(generator "pcbnew")
	(generator_version "10.0")
	(general
		(thickness 1.6)
		(legacy_teardrops no)
	)
	(paper "A4")
	(title_block
		(title "04192023_DAF0TMB3IC0_F0TG_MB_C_brd_V02_OCP.brd")
		(comment 1 "Grand Teton / footprints 2213-2219 of 8354")
	)
	(layers
		(0 "F.Cu" signal "TOP")
		(4 "In1.Cu" signal "GND")
		(6 "In2.Cu" signal "IN1")
		(8 "In3.Cu" signal "GND1")
		(10 "In4.Cu" signal "IN2")
		(12 "In5.Cu" signal "GND2")
		(14 "In6.Cu" signal "IN3")
		(16 "In7.Cu" signal "GND3")
		(18 "In8.Cu" signal "VCC")
		(20 "In9.Cu" signal "VCC1")
		(22 "In10.Cu" signal "GND4")
		(24 "In11.Cu" signal "IN4")
		(26 "In12.Cu" signal "GND5")
		(28 "In13.Cu" signal "IN5")
		(30 "In14.Cu" signal "GND6")
		(32 "In15.Cu" signal "IN6")
		(34 "In16.Cu" signal "GND7")
		(2 "B.Cu" signal "BOTTOM")
		(9 "F.Adhes" user "F.Adhesive")
		(11 "B.Adhes" user "B.Adhesive")
		(13 "F.Paste" user "Package Geometry/Pastemask Top")
		(15 "B.Paste" user "Package Geometry/Pastemask Bottom")
		(5 "F.SilkS" user "Ref Des/Silkscreen Top")
		(7 "B.SilkS" user "Ref Des/Silkscreen Bottom")
		(1 "F.Mask" user "Board Geometry/Soldermask Top")
		(3 "B.Mask" user "Board Geometry/Soldermask Bottom")
		(17 "Dwgs.User" user "User.Drawings")
		(19 "Cmts.User" user "User.Comments")
		(21 "Eco1.User" user "User.Eco1")
		(23 "Eco2.User" user "User.Eco2")
		(25 "Edge.Cuts" user "Board Geometry/Outline")
		(27 "Margin" user)
		(31 "F.CrtYd" user "Package Geometry/Place Bound Top")
		(29 "B.CrtYd" user "Package Geometry/Place Bound Bottom")
		(35 "F.Fab" user "Ref Des/Assembly Top")
		(33 "B.Fab" user "Ref Des/Assembly Bottom")
	)
	(footprint ""
		(layer "F.Cu")
		(at 80.924146 -24.346408 180)
		(property "Reference" "C40"
			(at 0 0 180)
			(layer "F.SilkS")
			(hide yes)
			(effects
				(font
					(size 1.27 1.27)
				)
			)
		)
		(property "Value" ""
			(at 0 0 180)
			(layer "F.Fab")
			(effects
				(font
					(size 1.27 1.27)
				)
			)
		)
		(duplicate_pad_numbers_are_jumpers no)
		(fp_line
			(start 0.7874 0.4064)
			(end -0.7874 0.4064)
			(stroke
				(width 0.1524)
				(type default)
			)
			(layer "F.SilkS")
		)
		(fp_line
			(start 0.7874 -0.4064)
			(end 0.7874 0.4064)
			(stroke
				(width 0.1524)
				(type default)
			)
			(layer "F.SilkS")
		)
		(fp_line
			(start -0.7874 0.4064)
			(end -0.7874 -0.4064)
			(stroke
				(width 0.1524)
				(type default)
			)
			(layer "F.SilkS")
		)
		(fp_line
			(start -0.7874 -0.4064)
			(end 0.7874 -0.4064)
			(stroke
				(width 0.1524)
				(type default)
			)
			(layer "F.SilkS")
		)
		(fp_line
			(start 0.67945 0.3048)
			(end 0.120396 0.3048)
			(stroke
				(width 0.1)
				(type default)
			)
			(layer "F.Fab")
		)
		(fp_line
			(start 0.67945 -0.3048)
			(end 0.67945 0.3048)
			(stroke
				(width 0.1)
				(type default)
			)
			(layer "F.Fab")
		)
		(fp_line
			(start 0.12065 -0.2794)
			(end 0.12065 -0.3048)
			(stroke
				(width 0.1)
				(type default)
			)
			(layer "F.Fab")
		)
		(fp_line
			(start 0.12065 -0.3048)
			(end 0.67945 -0.3048)
			(stroke
				(width 0.1)
				(type default)
			)
			(layer "F.Fab")
		)
		(fp_line
			(start 0.120396 0.3048)
			(end 0.120396 0.2794)
			(stroke
				(width 0.1)
				(type default)
			)
			(layer "F.Fab")
		)
		(fp_line
			(start 0.120396 0.2794)
			(end -0.12065 0.2794)
			(stroke
				(width 0.1)
				(type default)
			)
			(layer "F.Fab")
		)
		(fp_line
			(start -0.12065 0.3048)
			(end -0.67945 0.3048)
			(stroke
				(width 0.1)
				(type default)
			)
			(layer "F.Fab")
		)
		(fp_line
			(start -0.12065 0.2794)
			(end -0.12065 0.3048)
			(stroke
				(width 0.1)
				(type default)
			)
			(layer "F.Fab")
		)
		(fp_line
			(start -0.12065 -0.2794)
			(end 0.12065 -0.2794)
			(stroke
				(width 0.1)
				(type default)
			)
			(layer "F.Fab")
		)
		(fp_line
			(start -0.12065 -0.305054)
			(end -0.12065 -0.2794)
			(stroke
				(width 0.1)
				(type default)
			)
			(layer "F.Fab")
		)
		(fp_line
			(start -0.67945 0.3048)
			(end -0.67945 -0.305054)
			(stroke
				(width 0.1)
				(type default)
			)
			(layer "F.Fab")
		)
		(fp_line
			(start -0.67945 -0.305054)
			(end -0.12065 -0.305054)
			(stroke
				(width 0.1)
				(type default)
			)
			(layer "F.Fab")
		)
		(pad "1" smd circle
			(at -0.40005 0 180)
			(size 0 0)
			(layers "F.Cu" "F.Mask" "F.Paste")
			(net "P12V_OCP_V3_2")
		)
		(pad "2" smd circle
			(at 0.40005 0 180)
			(size 0 0)
			(layers "F.Cu" "F.Mask" "F.Paste")
			(net "P12V_OCP_GATE_2")
		)
	)
	(footprint ""
		(layer "F.Cu")
		(at 462.147666 -380.13767 -90)
		(property "Reference" "PC6572"
			(at 4.62534 2.153666 0)
			(unlocked yes)
			(layer "F.SilkS")
			(effects
				(font
					(size 0.7874 0.5842)
					(thickness 0.1524)
				)
				(justify left)
			)
		)
		(property "Value" ""
			(at 0 0 270)
			(layer "F.Fab")
			(effects
				(font
					(size 1.27 1.27)
				)
			)
		)
		(duplicate_pad_numbers_are_jumpers no)
		(fp_line
			(start -1.988058 2.750058)
			(end 2.750058 2.750058)
			(stroke
				(width 0.1524)
				(type default)
			)
			(layer "F.SilkS")
		)
		(fp_line
			(start 2.750058 2.750058)
			(end 2.750058 0.9398)
			(stroke
				(width 0.1524)
				(type default)
			)
			(layer "F.SilkS")
		)
		(fp_line
			(start -2.750058 1.988058)
			(end -1.988058 2.750058)
			(stroke
				(width 0.1524)
				(type default)
			)
			(layer "F.SilkS")
		)
		(fp_line
			(start -2.750058 0.9398)
			(end -2.750058 1.988058)
			(stroke
				(width 0.1524)
				(type default)
			)
			(layer "F.SilkS")
		)
		(fp_line
			(start 2.750058 -0.9398)
			(end 2.750058 -2.750058)
			(stroke
				(width 0.1524)
				(type default)
			)
			(layer "F.SilkS")
		)
		(fp_line
			(start -2.750058 -1.988058)
			(end -2.750058 -0.9398)
			(stroke
				(width 0.1524)
				(type default)
			)
			(layer "F.SilkS")
		)
		(fp_line
			(start -1.988058 -2.750058)
			(end -2.750058 -1.988058)
			(stroke
				(width 0.1524)
				(type default)
			)
			(layer "F.SilkS")
		)
		(fp_line
			(start 2.750058 -2.750058)
			(end -1.988058 -2.750058)
			(stroke
				(width 0.1524)
				(type default)
			)
			(layer "F.SilkS")
		)
		(fp_line
			(start -2.750058 2.750058)
			(end 2.750058 2.750058)
			(stroke
				(width 0.1)
				(type default)
			)
			(layer "F.Fab")
		)
		(fp_line
			(start 2.750058 2.750058)
			(end 2.750058 -2.750058)
			(stroke
				(width 0.1)
				(type default)
			)
			(layer "F.Fab")
		)
		(fp_line
			(start -2.750058 -2.750058)
			(end -2.750058 2.750058)
			(stroke
				(width 0.1)
				(type default)
			)
			(layer "F.Fab")
		)
		(fp_line
			(start 2.750058 -2.750058)
			(end -2.750058 -2.750058)
			(stroke
				(width 0.1)
				(type default)
			)
			(layer "F.Fab")
		)
		(pad "1" smd rect
			(at -2.199894 0)
			(size 1.6002 3.0226)
			(layers "F.Cu" "F.Mask" "F.Paste")
			(net "P0V9_CPU0_RT_2D")
		)
		(pad "2" smd rect
			(at 2.199894 0)
			(size 1.6002 3.0226)
			(layers "F.Cu" "F.Mask" "F.Paste")
			(net "GND")
		)
	)
	(footprint ""
		(layer "F.Cu")
		(at 80.762094 -152.999694 90)
		(property "Reference" "PC8003"
			(at 0 0 90)
			(layer "F.SilkS")
			(hide yes)
			(effects
				(font
					(size 1.27 1.27)
				)
			)
		)
		(property "Value" ""
			(at 0 0 90)
			(layer "F.Fab")
			(effects
				(font
					(size 1.27 1.27)
				)
			)
		)
		(duplicate_pad_numbers_are_jumpers no)
		(fp_line
			(start 1.524 -0.762)
			(end 1.524 0.762)
			(stroke
				(width 0.1524)
				(type default)
			)
			(layer "F.SilkS")
		)
		(fp_line
			(start -1.524 -0.762)
			(end 1.524 -0.762)
			(stroke
				(width 0.1524)
				(type default)
			)
			(layer "F.SilkS")
		)
		(fp_line
			(start 1.524 0.762)
			(end -1.524 0.762)
			(stroke
				(width 0.1524)
				(type default)
			)
			(layer "F.SilkS")
		)
		(fp_line
			(start -1.524 0.762)
			(end -1.524 -0.762)
			(stroke
				(width 0.1524)
				(type default)
			)
			(layer "F.SilkS")
		)
		(fp_line
			(start 1.1049 -0.724916)
			(end -1.1049 -0.724916)
			(stroke
				(width 0.1)
				(type default)
			)
			(layer "F.Fab")
		)
		(fp_line
			(start -1.1049 -0.724916)
			(end -1.1049 0.724916)
			(stroke
				(width 0.1)
				(type default)
			)
			(layer "F.Fab")
		)
		(fp_line
			(start 1.1049 0.724916)
			(end 1.1049 -0.724916)
			(stroke
				(width 0.1)
				(type default)
			)
			(layer "F.Fab")
		)
		(fp_line
			(start -1.1049 0.724916)
			(end 1.1049 0.724916)
			(stroke
				(width 0.1)
				(type default)
			)
			(layer "F.Fab")
		)
		(pad "1" smd rect
			(at -0.889 0 270)
			(size 1.016 1.27)
			(layers "F.Cu" "F.Mask" "F.Paste")
			(net "SW_P12V_AUX_PVDD18_S5_P1_FLT")
		)
		(pad "2" smd rect
			(at 0.889 0 270)
			(size 1.016 1.27)
			(layers "F.Cu" "F.Mask" "F.Paste")
			(net "GND")
		)
	)
	(footprint ""
		(layer "F.Cu")
		(at 114.327178 -261.748016 -90)
		(property "Reference" "C2501"
			(at 0 0 270)
			(layer "F.SilkS")
			(hide yes)
			(effects
				(font
					(size 1.27 1.27)
				)
			)
		)
		(property "Value" ""
			(at 0 0 270)
			(layer "F.Fab")
			(effects
				(font
					(size 1.27 1.27)
				)
			)
		)
		(duplicate_pad_numbers_are_jumpers no)
		(fp_line
			(start -0.7874 0.4064)
			(end -0.7874 -0.4064)
			(stroke
				(width 0.1524)
				(type default)
			)
			(layer "F.SilkS")
		)
		(fp_line
			(start 0.7874 0.4064)
			(end -0.7874 0.4064)
			(stroke
				(width 0.1524)
				(type default)
			)
			(layer "F.SilkS")
		)
		(fp_line
			(start -0.7874 -0.4064)
			(end 0.7874 -0.4064)
			(stroke
				(width 0.1524)
				(type default)
			)
			(layer "F.SilkS")
		)
		(fp_line
			(start 0.7874 -0.4064)
			(end 0.7874 0.4064)
			(stroke
				(width 0.1524)
				(type default)
			)
			(layer "F.SilkS")
		)
		(fp_line
			(start -0.67945 0.3048)
			(end -0.67945 -0.305054)
			(stroke
				(width 0.1)
				(type default)
			)
			(layer "F.Fab")
		)
		(fp_line
			(start -0.12065 0.3048)
			(end -0.67945 0.3048)
			(stroke
				(width 0.1)
				(type default)
			)
			(layer "F.Fab")
		)
		(fp_line
			(start 0.120396 0.3048)
			(end 0.120396 0.2794)
			(stroke
				(width 0.1)
				(type default)
			)
			(layer "F.Fab")
		)
		(fp_line
			(start 0.67945 0.3048)
			(end 0.120396 0.3048)
			(stroke
				(width 0.1)
				(type default)
			)
			(layer "F.Fab")
		)
		(fp_line
			(start -0.12065 0.2794)
			(end -0.12065 0.3048)
			(stroke
				(width 0.1)
				(type default)
			)
			(layer "F.Fab")
		)
		(fp_line
			(start 0.120396 0.2794)
			(end -0.12065 0.2794)
			(stroke
				(width 0.1)
				(type default)
			)
			(layer "F.Fab")
		)
		(fp_line
			(start -0.12065 -0.2794)
			(end 0.12065 -0.2794)
			(stroke
				(width 0.1)
				(type default)
			)
			(layer "F.Fab")
		)
		(fp_line
			(start 0.12065 -0.2794)
			(end 0.12065 -0.3048)
			(stroke
				(width 0.1)
				(type default)
			)
			(layer "F.Fab")
		)
		(fp_line
			(start 0.12065 -0.3048)
			(end 0.67945 -0.3048)
			(stroke
				(width 0.1)
				(type default)
			)
			(layer "F.Fab")
		)
		(fp_line
			(start 0.67945 -0.3048)
			(end 0.67945 0.3048)
			(stroke
				(width 0.1)
				(type default)
			)
			(layer "F.Fab")
		)
		(fp_line
			(start -0.67945 -0.305054)
			(end -0.12065 -0.305054)
			(stroke
				(width 0.1)
				(type default)
			)
			(layer "F.Fab")
		)
		(fp_line
			(start -0.12065 -0.305054)
			(end -0.12065 -0.2794)
			(stroke
				(width 0.1)
				(type default)
			)
			(layer "F.Fab")
		)
		(pad "1" smd circle
			(at -0.40005 0 270)
			(size 0 0)
			(layers "F.Cu" "F.Mask" "F.Paste")
			(net "PVDD11_S3_P1")
		)
		(pad "2" smd circle
			(at 0.40005 0 270)
			(size 0 0)
			(layers "F.Cu" "F.Mask" "F.Paste")
			(net "GND")
		)
	)
	(footprint ""
		(layer "F.Cu")
		(at 248.46915 -271.267936 180)
		(property "Reference" "PL6500"
			(at 5.77215 -3.197606 0)
			(unlocked yes)
			(layer "F.SilkS")
			(effects
				(font
					(size 0.7874 0.5842)
					(thickness 0.1524)
				)
				(justify left)
			)
		)
		(property "Value" ""
			(at 0 0 180)
			(layer "F.Fab")
			(effects
				(font
					(size 1.27 1.27)
				)
			)
		)
		(duplicate_pad_numbers_are_jumpers no)
		(fp_line
			(start 2.249932 2.249932)
			(end -2.249932 2.249932)
			(stroke
				(width 0.1524)
				(type default)
			)
			(layer "F.SilkS")
		)
		(fp_line
			(start 2.249932 1.3843)
			(end 2.249932 2.249932)
			(stroke
				(width 0.1524)
				(type default)
			)
			(layer "F.SilkS")
		)
		(fp_line
			(start 2.249932 -2.249932)
			(end 2.249932 -1.3843)
			(stroke
				(width 0.1524)
				(type default)
			)
			(layer "F.SilkS")
		)
		(fp_line
			(start -2.249932 2.249932)
			(end -2.249932 1.3843)
			(stroke
				(width 0.1524)
				(type default)
			)
			(layer "F.SilkS")
		)
		(fp_line
			(start -2.249932 -1.3843)
			(end -2.249932 -2.249932)
			(stroke
				(width 0.1524)
				(type default)
			)
			(layer "F.SilkS")
		)
		(fp_line
			(start -2.249932 -2.249932)
			(end 2.249932 -2.249932)
			(stroke
				(width 0.1524)
				(type default)
			)
			(layer "F.SilkS")
		)
		(fp_line
			(start 2.249932 2.249932)
			(end -2.249932 2.249932)
			(stroke
				(width 0.1)
				(type default)
			)
			(layer "F.Fab")
		)
		(fp_line
			(start 2.249932 -2.249932)
			(end 2.249932 2.249932)
			(stroke
				(width 0.1)
				(type default)
			)
			(layer "F.Fab")
		)
		(fp_line
			(start -2.249932 2.249932)
			(end -2.249932 -2.249932)
			(stroke
				(width 0.1)
				(type default)
			)
			(layer "F.Fab")
		)
		(fp_line
			(start -2.249932 -2.249932)
			(end 2.249932 -2.249932)
			(stroke
				(width 0.1)
				(type default)
			)
			(layer "F.Fab")
		)
		(pad "1" smd rect
			(at -1.82499 0 180)
			(size 1.0668 2.5146)
			(layers "F.Cu" "F.Mask" "F.Paste")
			(net "P12V_AUX")
		)
		(pad "2" smd rect
			(at 1.82499 0 180)
			(size 1.0668 2.5146)
			(layers "F.Cu" "F.Mask" "F.Paste")
			(net "SW_P12V_AUX_P1V8_RETIMER_CPU0_FLT")
		)
	)
	(footprint ""
		(layer "F.Cu")
		(at 159.18307 -76.53147 -90)
		(property "Reference" "R994"
			(at 0 0 270)
			(layer "F.SilkS")
			(hide yes)
			(effects
				(font
					(size 1.27 1.27)
				)
			)
		)
		(property "Value" ""
			(at 0 0 270)
			(layer "F.Fab")
			(effects
				(font
					(size 1.27 1.27)
				)
			)
		)
		(duplicate_pad_numbers_are_jumpers no)
		(fp_line
			(start -0.7874 0.4064)
			(end -0.7874 -0.4064)
			(stroke
				(width 0.1524)
				(type default)
			)
			(layer "F.SilkS")
		)
		(fp_line
			(start 0.7874 0.4064)
			(end -0.7874 0.4064)
			(stroke
				(width 0.1524)
				(type default)
			)
			(layer "F.SilkS")
		)
		(fp_line
			(start -0.7874 -0.4064)
			(end 0.7874 -0.4064)
			(stroke
				(width 0.1524)
				(type default)
			)
			(layer "F.SilkS")
		)
		(fp_line
			(start 0.7874 -0.4064)
			(end 0.7874 0.4064)
			(stroke
				(width 0.1524)
				(type default)
			)
			(layer "F.SilkS")
		)
		(fp_line
			(start -0.67945 0.3048)
			(end -0.67945 -0.305054)
			(stroke
				(width 0.1)
				(type default)
			)
			(layer "F.Fab")
		)
		(fp_line
			(start -0.12065 0.3048)
			(end -0.67945 0.3048)
			(stroke
				(width 0.1)
				(type default)
			)
			(layer "F.Fab")
		)
		(fp_line
			(start 0.120396 0.3048)
			(end 0.120396 0.2794)
			(stroke
				(width 0.1)
				(type default)
			)
			(layer "F.Fab")
		)
		(fp_line
			(start 0.67945 0.3048)
			(end 0.120396 0.3048)
			(stroke
				(width 0.1)
				(type default)
			)
			(layer "F.Fab")
		)
		(fp_line
			(start -0.12065 0.2794)
			(end -0.12065 0.3048)
			(stroke
				(width 0.1)
				(type default)
			)
			(layer "F.Fab")
		)
		(fp_line
			(start 0.120396 0.2794)
			(end -0.12065 0.2794)
			(stroke
				(width 0.1)
				(type default)
			)
			(layer "F.Fab")
		)
		(fp_line
			(start -0.12065 -0.2794)
			(end 0.12065 -0.2794)
			(stroke
				(width 0.1)
				(type default)
			)
			(layer "F.Fab")
		)
		(fp_line
			(start 0.12065 -0.2794)
			(end 0.12065 -0.3048)
			(stroke
				(width 0.1)
				(type default)
			)
			(layer "F.Fab")
		)
		(fp_line
			(start 0.12065 -0.3048)
			(end 0.67945 -0.3048)
			(stroke
				(width 0.1)
				(type default)
			)
			(layer "F.Fab")
		)
		(fp_line
			(start 0.67945 -0.3048)
			(end 0.67945 0.3048)
			(stroke
				(width 0.1)
				(type default)
			)
			(layer "F.Fab")
		)
		(fp_line
			(start -0.67945 -0.305054)
			(end -0.12065 -0.305054)
			(stroke
				(width 0.1)
				(type default)
			)
			(layer "F.Fab")
		)
		(fp_line
			(start -0.12065 -0.305054)
			(end -0.12065 -0.2794)
			(stroke
				(width 0.1)
				(type default)
			)
			(layer "F.Fab")
		)
		(pad "1" smd circle
			(at -0.40005 0 270)
			(size 0 0)
			(layers "F.Cu" "F.Mask" "F.Paste")
			(net "P3V3_AUX")
		)
		(pad "2" smd circle
			(at 0.40005 0 270)
			(size 0 0)
			(layers "F.Cu" "F.Mask" "F.Paste")
			(net "IRQ_LVC3_WAKE_N")
		)
	)
	(footprint ""
		(layer "F.Cu")
		(at 428.120302 -434.386736 90)
		(property "Reference" "R2933"
			(at 0 0 90)
			(layer "F.SilkS")
			(hide yes)
			(effects
				(font
					(size 1.27 1.27)
				)
			)
		)
		(property "Value" ""
			(at 0 0 90)
			(layer "F.Fab")
			(effects
				(font
					(size 1.27 1.27)
				)
			)
		)
		(duplicate_pad_numbers_are_jumpers no)
		(fp_line
			(start 0.7874 -0.4064)
			(end 0.7874 0.4064)
			(stroke
				(width 0.1524)
				(type default)
			)
			(layer "F.SilkS")
		)
		(fp_line
			(start -0.7874 -0.4064)
			(end 0.7874 -0.4064)
			(stroke
				(width 0.1524)
				(type default)
			)
			(layer "F.SilkS")
		)
		(fp_line
			(start 0.7874 0.4064)
			(end -0.7874 0.4064)
			(stroke
				(width 0.1524)
				(type default)
			)
			(layer "F.SilkS")
		)
		(fp_line
			(start -0.7874 0.4064)
			(end -0.7874 -0.4064)
			(stroke
				(width 0.1524)
				(type default)
			)
			(layer "F.SilkS")
		)
		(fp_line
			(start -0.12065 -0.305054)
			(end -0.12065 -0.2794)
			(stroke
				(width 0.1)
				(type default)
			)
			(layer "F.Fab")
		)
		(fp_line
			(start -0.67945 -0.305054)
			(end -0.12065 -0.305054)
			(stroke
				(width 0.1)
				(type default)
			)
			(layer "F.Fab")
		)
		(fp_line
			(start 0.67945 -0.3048)
			(end 0.67945 0.3048)
			(stroke
				(width 0.1)
				(type default)
			)
			(layer "F.Fab")
		)
		(fp_line
			(start 0.12065 -0.3048)
			(end 0.67945 -0.3048)
			(stroke
				(width 0.1)
				(type default)
			)
			(layer "F.Fab")
		)
		(fp_line
			(start 0.12065 -0.2794)
			(end 0.12065 -0.3048)
			(stroke
				(width 0.1)
				(type default)
			)
			(layer "F.Fab")
		)
		(fp_line
			(start -0.12065 -0.2794)
			(end 0.12065 -0.2794)
			(stroke
				(width 0.1)
				(type default)
			)
			(layer "F.Fab")
		)
		(fp_line
			(start 0.120396 0.2794)
			(end -0.12065 0.2794)
			(stroke
				(width 0.1)
				(type default)
			)
			(layer "F.Fab")
		)
		(fp_line
			(start -0.12065 0.2794)
			(end -0.12065 0.3048)
			(stroke
				(width 0.1)
				(type default)
			)
			(layer "F.Fab")
		)
		(fp_line
			(start 0.67945 0.3048)
			(end 0.120396 0.3048)
			(stroke
				(width 0.1)
				(type default)
			)
			(layer "F.Fab")
		)
		(fp_line
			(start 0.120396 0.3048)
			(end 0.120396 0.2794)
			(stroke
				(width 0.1)
				(type default)
			)
			(layer "F.Fab")
		)
		(fp_line
			(start -0.12065 0.3048)
			(end -0.67945 0.3048)
			(stroke
				(width 0.1)
				(type default)
			)
			(layer "F.Fab")
		)
		(fp_line
			(start -0.67945 0.3048)
			(end -0.67945 -0.305054)
			(stroke
				(width 0.1)
				(type default)
			)
			(layer "F.Fab")
		)
		(pad "1" smd circle
			(at -0.40005 0 90)
			(size 0 0)
			(layers "F.Cu" "F.Mask" "F.Paste")
			(net "P3V3_AUX")
		)
		(pad "2" smd circle
			(at 0.40005 0 90)
			(size 0 0)
			(layers "F.Cu" "F.Mask" "F.Paste")
			(net "FM_SWB_BIC_READY_ISO_N")
		)
	)
)
